# T6G (Grand Teton) — schematic netlist excerpt (pin names and nets, part order shuffled) for the footprints in the layout excerpt that follows; sources: Cadence DE-HDL packaged netlist, KiCad conversion of 04192023_DAF0TMB3IC0_F0TG_MB_C_brd_V02_OCP.brd

R1227  Q_RES  0 5% EMPTY  pkg 0402LF  page 258 : A = SMB_ADC_SDA_R ; B = SMB_SEN_MAM_2_3V3AUX_SDA
C2587  Q_CAP  22UF 4V 20% X6S  pkg C0402  page 70 : A = PVDDCR_SOC_P0 ; B = GND

(kicad_pcb
	(version 20260206)
	(generator "pcbnew")
	(generator_version "10.0")
	(general
		(thickness 1.6)
		(legacy_teardrops no)
	)
	(paper "A4")
	(title_block
		(title "04192023_DAF0TMB3IC0_F0TG_MB_C_brd_V02_OCP.brd")
		(comment 1 "Grand Teton / footprints 6813-6814 of 8354")
	)
	(layers
		(0 "F.Cu" signal "TOP")
		(4 "In1.Cu" signal "GND")
		(6 "In2.Cu" signal "IN1")
		(8 "In3.Cu" signal "GND1")
		(10 "In4.Cu" signal "IN2")
		(12 "In5.Cu" signal "GND2")
		(14 "In6.Cu" signal "IN3")
		(16 "In7.Cu" signal "GND3")
		(18 "In8.Cu" signal "VCC")
		(20 "In9.Cu" signal "VCC1")
		(22 "In10.Cu" signal "GND4")
		(24 "In11.Cu" signal "IN4")
		(26 "In12.Cu" signal "GND5")
		(28 "In13.Cu" signal "IN5")
		(30 "In14.Cu" signal "GND6")
		(32 "In15.Cu" signal "IN6")
		(34 "In16.Cu" signal "GND7")
		(2 "B.Cu" signal "BOTTOM")
		(9 "F.Adhes" user "F.Adhesive")
		(11 "B.Adhes" user "B.Adhesive")
		(13 "F.Paste" user "Package Geometry/Pastemask Top")
		(15 "B.Paste" user "Package Geometry/Pastemask Bottom")
		(5 "F.SilkS" user "Ref Des/Silkscreen Top")
		(7 "B.SilkS" user "Ref Des/Silkscreen Bottom")
		(1 "F.Mask" user "Board Geometry/Soldermask Top")
		(3 "B.Mask" user "Board Geometry/Soldermask Bottom")
		(17 "Dwgs.User" user "User.Drawings")
		(19 "Cmts.User" user "User.Comments")
		(21 "Eco1.User" user "User.Eco1")
		(23 "Eco2.User" user "User.Eco2")
		(25 "Edge.Cuts" user "Board Geometry/Outline")
		(27 "Margin" user)
		(31 "F.CrtYd" user "Package Geometry/Place Bound Top")
		(29 "B.CrtYd" user "Package Geometry/Place Bound Bottom")
		(35 "F.Fab" user "Ref Des/Assembly Top")
		(33 "B.Fab" user "Ref Des/Assembly Bottom")
	)
	(footprint ""
		(layer "B.Cu")
		(at 243.713 -326.898 180)
		(property "Reference" "R1227"
			(at 0 0 0)
			(layer "B.SilkS")
			(hide yes)
			(effects
				(font
					(size 1.27 1.27)
				)
				(justify mirror)
			)
		)
		(property "Value" ""
			(at 0 0 0)
			(layer "B.Fab")
			(effects
				(font
					(size 1.27 1.27)
				)
				(justify mirror)
			)
		)
		(duplicate_pad_numbers_are_jumpers no)
		(fp_line
			(start 0.7874 0.4064)
			(end 0.7874 -0.4064)
			(stroke
				(width 0.1524)
				(type default)
			)
			(layer "B.SilkS")
		)
		(fp_line
			(start 0.7874 -0.4064)
			(end -0.7874 -0.4064)
			(stroke
				(width 0.1524)
				(type default)
			)
			(layer "B.SilkS")
		)
		(fp_line
			(start -0.7874 0.4064)
			(end 0.7874 0.4064)
			(stroke
				(width 0.1524)
				(type default)
			)
			(layer "B.SilkS")
		)
		(fp_line
			(start -0.7874 -0.4064)
			(end -0.7874 0.4064)
			(stroke
				(width 0.1524)
				(type default)
			)
			(layer "B.SilkS")
		)
		(fp_line
			(start 0.67945 0.3048)
			(end 0.67945 -0.305054)
			(stroke
				(width 0.1)
				(type default)
			)
			(layer "B.Fab")
		)
		(fp_line
			(start 0.67945 -0.305054)
			(end 0.12065 -0.305054)
			(stroke
				(width 0.1)
				(type default)
			)
			(layer "B.Fab")
		)
		(fp_line
			(start 0.12065 0.3048)
			(end 0.67945 0.3048)
			(stroke
				(width 0.1)
				(type default)
			)
			(layer "B.Fab")
		)
		(fp_line
			(start 0.12065 0.2794)
			(end 0.12065 0.3048)
			(stroke
				(width 0.1)
				(type default)
			)
			(layer "B.Fab")
		)
		(fp_line
			(start 0.12065 -0.2794)
			(end -0.12065 -0.2794)
			(stroke
				(width 0.1)
				(type default)
			)
			(layer "B.Fab")
		)
		(fp_line
			(start 0.12065 -0.305054)
			(end 0.12065 -0.2794)
			(stroke
				(width 0.1)
				(type default)
			)
			(layer "B.Fab")
		)
		(fp_line
			(start -0.120396 0.3048)
			(end -0.120396 0.2794)
			(stroke
				(width 0.1)
				(type default)
			)
			(layer "B.Fab")
		)
		(fp_line
			(start -0.120396 0.2794)
			(end 0.12065 0.2794)
			(stroke
				(width 0.1)
				(type default)
			)
			(layer "B.Fab")
		)
		(fp_line
			(start -0.12065 -0.2794)
			(end -0.12065 -0.3048)
			(stroke
				(width 0.1)
				(type default)
			)
			(layer "B.Fab")
		)
		(fp_line
			(start -0.12065 -0.3048)
			(end -0.67945 -0.3048)
			(stroke
				(width 0.1)
				(type default)
			)
			(layer "B.Fab")
		)
		(fp_line
			(start -0.67945 0.3048)
			(end -0.120396 0.3048)
			(stroke
				(width 0.1)
				(type default)
			)
			(layer "B.Fab")
		)
		(fp_line
			(start -0.67945 -0.3048)
			(end -0.67945 0.3048)
			(stroke
				(width 0.1)
				(type default)
			)
			(layer "B.Fab")
		)
		(pad "1" smd circle
			(at 0.40005 0)
			(size 0 0)
			(layers "B.Cu" "B.Mask" "B.Paste")
			(net "SMB_ADC_SDA_R")
		)
		(pad "2" smd circle
			(at -0.40005 0)
			(size 0 0)
			(layers "B.Cu" "B.Mask" "B.Paste")
			(net "SMB_SEN_MAM_2_3V3AUX_SDA")
		)
	)
	(footprint ""
		(layer "B.Cu")
		(at 365.835692 -257.455162)
		(property "Reference" "C2587"
			(at 0 0 0)
			(layer "B.SilkS")
			(hide yes)
			(effects
				(font
					(size 1.27 1.27)
				)
				(justify mirror)
			)
		)
		(property "Value" ""
			(at 0 0 0)
			(layer "B.Fab")
			(effects
				(font
					(size 1.27 1.27)
				)
				(justify mirror)
			)
		)
		(duplicate_pad_numbers_are_jumpers no)
		(fp_line
			(start -0.7874 -0.4064)
			(end -0.7874 0.4064)
			(stroke
				(width 0.1524)
				(type default)
			)
			(layer "B.SilkS")
		)
		(fp_line
			(start -0.7874 0.4064)
			(end 0.7874 0.4064)
			(stroke
				(width 0.1524)
				(type default)
			)
			(layer "B.SilkS")
		)
		(fp_line
			(start 0.7874 -0.4064)
			(end -0.7874 -0.4064)
			(stroke
				(width 0.1524)
				(type default)
			)
			(layer "B.SilkS")
		)
		(fp_line
			(start 0.7874 0.4064)
			(end 0.7874 -0.4064)
			(stroke
				(width 0.1524)
				(type default)
			)
			(layer "B.SilkS")
		)
		(fp_line
			(start -0.67945 -0.3048)
			(end -0.67945 0.3048)
			(stroke
				(width 0.1)
				(type default)
			)
			(layer "B.Fab")
		)
		(fp_line
			(start -0.67945 0.3048)
			(end -0.120396 0.3048)
			(stroke
				(width 0.1)
				(type default)
			)
			(layer "B.Fab")
		)
		(fp_line
			(start -0.12065 -0.3048)
			(end -0.67945 -0.3048)
			(stroke
				(width 0.1)
				(type default)
			)
			(layer "B.Fab")
		)
		(fp_line
			(start -0.12065 -0.2794)
			(end -0.12065 -0.3048)
			(stroke
				(width 0.1)
				(type default)
			)
			(layer "B.Fab")
		)
		(fp_line
			(start -0.120396 0.2794)
			(end 0.12065 0.2794)
			(stroke
				(width 0.1)
				(type default)
			)
			(layer "B.Fab")
		)
		(fp_line
			(start -0.120396 0.3048)
			(end -0.120396 0.2794)
			(stroke
				(width 0.1)
				(type default)
			)
			(layer "B.Fab")
		)
		(fp_line
			(start 0.12065 -0.305054)
			(end 0.12065 -0.2794)
			(stroke
				(width 0.1)
				(type default)
			)
			(layer "B.Fab")
		)
		(fp_line
			(start 0.12065 -0.2794)
			(end -0.12065 -0.2794)
			(stroke
				(width 0.1)
				(type default)
			)
			(layer "B.Fab")
		)
		(fp_line
			(start 0.12065 0.2794)
			(end 0.12065 0.3048)
			(stroke
				(width 0.1)
				(type default)
			)
			(layer "B.Fab")
		)
		(fp_line
			(start 0.12065 0.3048)
			(end 0.67945 0.3048)
			(stroke
				(width 0.1)
				(type default)
			)
			(layer "B.Fab")
		)
		(fp_line
			(start 0.67945 -0.305054)
			(end 0.12065 -0.305054)
			(stroke
				(width 0.1)
				(type default)
			)
			(layer "B.Fab")
		)
		(fp_line
			(start 0.67945 0.3048)
			(end 0.67945 -0.305054)
			(stroke
				(width 0.1)
				(type default)
			)
			(layer "B.Fab")
		)
		(pad "1" smd circle
			(at 0.40005 0 180)
			(size 0 0)
			(layers "B.Cu" "B.Mask" "B.Paste")
			(net "PVDDCR_SOC_P0")
		)
		(pad "2" smd circle
			(at -0.40005 0 180)
			(size 0 0)
			(layers "B.Cu" "B.Mask" "B.Paste")
			(net "GND")
		)
	)
)
